#ISCELL
  logical_power design_note *
  *
#ISCELL
  mstr_misc dns *
  *
#ISCELL
  pure_quanta quanta_title_block_c *
  *
#ISCELL
  logical_power universal_gnd *
  page49_i1
#ISCELL
  standard offpage *
  page49_i10
#CELL
  pure_quanta 74lvc1g126se7 *
  page49_i11
#ISCELL
  logical_power universal_gnd *
  page49_i12
#CELL
  pure_quanta q_cap *
  page49_i13
#ISCELL
  logical_power vccaux15 *
  page49_i14
#ISCELL
  logical_power universal_gnd *
  page49_i16
#ISCELL
  logical_power vccaux15 *
  page49_i17
#ISCELL
  standard offpage *
  page49_i19
#ISCELL
  standard offpage *
  page49_i20
#ISCELL
  logical_power universal_gnd *
  page49_i21
#CELL
  pure_quanta q_res *
  page49_i22
#ISCELL
  logical_power universal_gnd *
  page49_i23
#CELL
  pure_quanta mosfet_dual_6p *
  page49_i24
#ISCELL
  logical_power universal_gnd *
  page49_i25
#CELL
  pure_quanta q_res *
  page49_i26
#ISCELL
  logical_power universal_gnd *
  page49_i27
#ISCELL
  standard offpage *
  page49_i28
#ISCELL
  standard offpage *
  page49_i29
#ISCELL
  logical_power universal_gnd *
  page49_i3
#ISCELL
  logical_power vccaux15 *
  page49_i31
#ISCELL
  standard offpage *
  page49_i32
#ISCELL
  standard offpage *
  page49_i33
#CELL
  pure_quanta q_res *
  page49_i34
#CELL
  pure_quanta q_res *
  page49_i35
#CELL
  pure_quanta q_res *
  page49_i36
#CELL
  pure_quanta q_cap *
  page49_i37
#CELL
  pure_quanta q_cap *
  page49_i38
#ISCELL
  logical_power universal_gnd *
  page49_i4
#CELL
  pure_quanta q_res *
  page49_i40
#CELL
  pure_quanta q_cap *
  page49_i43
#CELL
  pure_quanta q_cap *
  page49_i45
#ISCELL
  logical_power universal_gnd *
  page49_i46
#ISCELL
  logical_power universal_power *
  page49_i48
#ISCELL
  logical_power universal_gnd *
  page49_i49
#CELL
  pure_quanta mc74vhc1g32dtt1g *
  page49_i5
#CELL
  pure_quanta q_led *
  page49_i50
#CELL
  pure_quanta q_led *
  page49_i51
#ISCELL
  logical_power vccaux15 *
  page49_i52
#ISCELL
  standard offpage *
  page49_i55
#ISCELL
  standard offpage *
  page49_i56
#ISCELL
  logical_power universal_power *
  page49_i58
#CELL
  pure_quanta q_res *
  page49_i59
#CELL
  pure_quanta mosfet_nch_dual *
  page49_i6
#CELL
  pure_quanta q_res *
  page49_i60
#ISCELL
  logical_power universal_gnd *
  page49_i7
#CELL
  pure_quanta q_cap *
  page49_i75
#CELL
  pure_quanta q_res *
  page49_i79
#CELL
  pure_quanta q_res *
  page49_i8
#CELL
  pure_quanta q_res *
  page49_i88
#CELL
  pure_quanta q_res *
  page49_i89
#ISCELL
  standard offpage *
  page49_i9
#CELL
  pure_quanta q_res *
  page49_i92
#ISCELL
  standard offpage *
  page49_i93
#CELL
  pure_quanta q_led *
  page49_i94
#CELL
  pure_quanta q_led *
  page49_i95
#CELL
  pure_quanta q_led *
  page49_i97
